(kicad_pcb
	(version 20221018)
	(generator pcbnew)
	(general
    (thickness 1.518)
  )
	(paper "A4")
	(title_block
    (title "Kria K26 Devboard")
    (date "2024-03-26")
    (rev "1.2.5")
    (comment 1 "www.antmicro.com")
    (comment 2 "Antmicro Ltd.")
		(comment 9 "footprints 439-440 of 660")
	)
	(layers
    (0 "F.Cu" mixed)
    (1 "In1.Cu" power)
    (2 "In2.Cu" mixed)
    (3 "In3.Cu" power)
    (4 "In4.Cu" mixed)
    (5 "In5.Cu" power)
    (6 "In6.Cu" mixed)
    (31 "B.Cu" power)
    (32 "B.Adhes" user "B.Adhesive")
    (33 "F.Adhes" user "F.Adhesive")
    (34 "B.Paste" user)
    (35 "F.Paste" user)
    (36 "B.SilkS" user "B.Silkscreen")
    (37 "F.SilkS" user "F.Silkscreen")
    (38 "B.Mask" user)
    (39 "F.Mask" user)
    (40 "Dwgs.User" user "User.Drawings")
    (41 "Cmts.User" user "User.Comments")
    (42 "Eco1.User" user "User.Eco1")
    (43 "Eco2.User" user "User.Eco2")
    (44 "Edge.Cuts" user)
    (45 "Margin" user)
    (46 "B.CrtYd" user "B.Courtyard")
    (47 "F.CrtYd" user "F.Courtyard")
    (48 "B.Fab" user)
    (49 "F.Fab" user)
  )
	(footprint "kria-k26-devboard-footprints:Conn_FFC_WE_68715014x22_ALT" locked (layer "B.Cu")
    (at 79.76 102 90)
    (property "Author" "Antmicro")
    (property "License" "Apache-2.0")
    (property "MPN" "68715014522")
    (property "Manufacturer" "Würth Elektronik")
    (property "Sheetfile" "camera.kicad_sch")
    (property "Sheetname" "Camera interface")
    (property "VSD_Class" "Antmicro Dual Camera interface")
    (property "ki_description" "FFC connector")
    (property "ki_keywords" "CONNECTOR")
    (attr smd)
    (fp_text reference "J3" (at 0 6.4 270) (layer "B.SilkS")
        (effects (font (size 0.7 0.7) (thickness 0.15)) (justify left bottom mirror))
    )
    (fp_text value "Conn_FFC_WE_68715014522_CUSTOM_TWO-SIDES" (at -0.3 -3.899 270) (layer "B.Fab")
        (effects (font (size 0.7 0.7) (thickness 0.15)) (justify left bottom mirror))
    )
    (fp_text user "License: Apache-2.0" (at -15.861 -7.9 270) (layer "B.Fab") hide
        (effects (font (size 0.7 0.7) (thickness 0.15)) (justify left bottom mirror))
    )
    (fp_text user "${REFERENCE}" (at -15.861 -5.9 270) (layer "B.Fab") hide
        (effects (font (size 0.7 0.7) (thickness 0.15)) (justify left bottom mirror))
    )
    (fp_text user "Author: Antmicro" (at -15.861 -6.9 270) (layer "B.Fab") hide
        (effects (font (size 0.7 0.7) (thickness 0.15)) (justify left bottom mirror))
    )
    (fp_line (start -15.861 -1.298) (end -15.861 2.15)
      (stroke (width 0.15) (type solid)) (layer "B.SilkS"))
    (fp_line (start -15.83 2.15) (end -12.5 2.15)
      (stroke (width 0.15) (type solid)) (layer "B.SilkS"))
    (fp_line (start -12.561 -1.33) (end -15.84 -1.33)
      (stroke (width 0.15) (type solid)) (layer "B.SilkS"))
    (fp_line (start -12.5 1.325) (end -12.5 -1.33)
      (stroke (width 0.15) (type solid)) (layer "B.SilkS"))
    (fp_line (start -12.5 1.325) (end 12.499 1.325)
      (stroke (width 0.15) (type solid)) (layer "B.SilkS"))
    (fp_line (start -12.5 2.15) (end -12.5 3.4)
      (stroke (width 0.15) (type solid)) (layer "B.SilkS"))
    (fp_line (start -12.5 2.976) (end 12.499 2.976)
      (stroke (width 0.15) (type solid)) (layer "B.SilkS"))
    (fp_line (start 12.499 -1.29) (end 15.839 -1.29)
      (stroke (width 0.15) (type solid)) (layer "B.SilkS"))
    (fp_line (start 12.499 1.325) (end 12.499 -1.259)
      (stroke (width 0.15) (type solid)) (layer "B.SilkS"))
    (fp_line (start 12.499 2.15) (end 12.499 2.976)
      (stroke (width 0.15) (type solid)) (layer "B.SilkS"))
    (fp_line (start 15.81 2.15) (end 12.499 2.15)
      (stroke (width 0.15) (type solid)) (layer "B.SilkS"))
    (fp_line (start 15.839 -1.29) (end 15.839 2.15)
      (stroke (width 0.15) (type solid)) (layer "B.SilkS"))
    (fp_circle (center -12.25 3.86) (end -12.2 3.81)
      (stroke (width 0.15) (type solid)) (fill solid) (layer "B.SilkS"))
    (fp_rect (start -16.201 6.001) (end 16.198 -3.548)
      (stroke (width 0.05) (type solid)) (fill none) (layer "B.CrtYd"))
    (pad "1" smd roundrect locked (at -12.25 2.15 90) (size 0.3 1.2) (layers "B.Cu" "B.Paste" "B.Mask") (roundrect_rratio 0.25)
      (net 219 "/Camera interface/HPA04_N") (pintype "passive"))
    (pad "2" smd roundrect locked (at -11.75 2.15 90) (size 0.3 1.2) (layers "B.Cu" "B.Paste" "B.Mask") (roundrect_rratio 0.25)
      (net 218 "/Camera interface/HPA04_P") (pintype "passive"))
    (pad "3" smd roundrect locked (at -11.25 2.15 90) (size 0.3 1.2) (layers "B.Cu" "B.Paste" "B.Mask") (roundrect_rratio 0.25)
      (net 217 "/Camera interface/HPA03_N") (pintype "passive"))
    (pad "4" smd roundrect locked (at -10.75 2.15 90) (size 0.3 1.2) (layers "B.Cu" "B.Paste" "B.Mask") (roundrect_rratio 0.25)
      (net 216 "/Camera interface/HPA03_P") (pintype "passive"))
    (pad "5" smd roundrect locked (at -10.25 2.15 90) (size 0.3 1.2) (layers "B.Cu" "B.Paste" "B.Mask") (roundrect_rratio 0.25)
      (net 215 "/Camera interface/HPA02_N") (pintype "passive"))
    (pad "6" smd roundrect locked (at -9.75 2.15 90) (size 0.3 1.2) (layers "B.Cu" "B.Paste" "B.Mask") (roundrect_rratio 0.25)
      (net 214 "/Camera interface/HPA02_P") (pintype "passive"))
    (pad "7" smd roundrect locked (at -9.25 2.15 90) (size 0.3 1.2) (layers "B.Cu" "B.Paste" "B.Mask") (roundrect_rratio 0.25)
      (net 213 "/Camera interface/HPA01_N") (pintype "passive"))
    (pad "8" smd roundrect locked (at -8.75 2.15 90) (size 0.3 1.2) (layers "B.Cu" "B.Paste" "B.Mask") (roundrect_rratio 0.25)
      (net 212 "/Camera interface/HPA01_P") (pintype "passive"))
    (pad "9" smd roundrect locked (at -8.25 2.15 90) (size 0.3 1.2) (layers "B.Cu" "B.Paste" "B.Mask") (roundrect_rratio 0.25)
      (net 1 "GND") (pintype "passive"))
    (pad "10" smd roundrect locked (at -7.75 2.15 90) (size 0.3 1.2) (layers "B.Cu" "B.Paste" "B.Mask") (roundrect_rratio 0.25)
      (net 211 "/Camera interface/HPA00_CC_N") (pintype "passive"))
    (pad "11" smd roundrect locked (at -7.25 2.15 90) (size 0.3 1.2) (layers "B.Cu" "B.Paste" "B.Mask") (roundrect_rratio 0.25)
      (net 210 "/Camera interface/HPA00_CC_P") (pintype "passive"))
    (pad "12" smd roundrect locked (at -6.75 2.15 90) (size 0.3 1.2) (layers "B.Cu" "B.Paste" "B.Mask") (roundrect_rratio 0.25)
      (net 1 "GND") (pintype "passive"))
    (pad "13" smd roundrect locked (at -6.25 2.15 90) (size 0.3 1.2) (layers "B.Cu" "B.Paste" "B.Mask") (roundrect_rratio 0.25)
      (net 416 "unconnected-(J3-Pad13)") (pintype "passive+no_connect"))
    (pad "14" smd roundrect locked (at -5.75 2.15 90) (size 0.3 1.2) (layers "B.Cu" "B.Paste" "B.Mask") (roundrect_rratio 0.25)
      (net 417 "unconnected-(J3-Pad14)") (pintype "passive+no_connect"))
    (pad "15" smd roundrect locked (at -5.25 2.15 90) (size 0.3 1.2) (layers "B.Cu" "B.Paste" "B.Mask") (roundrect_rratio 0.25)
      (net 1 "GND") (pintype "passive"))
    (pad "16" smd roundrect locked (at -4.75 2.15 90) (size 0.3 1.2) (layers "B.Cu" "B.Paste" "B.Mask") (roundrect_rratio 0.25)
      (net 418 "unconnected-(J3-Pad16)") (pintype "passive+no_connect"))
    (pad "17" smd roundrect locked (at -4.25 2.15 90) (size 0.3 1.2) (layers "B.Cu" "B.Paste" "B.Mask") (roundrect_rratio 0.25)
      (net 419 "unconnected-(J3-Pad17)") (pintype "passive+no_connect"))
    (pad "18" smd roundrect locked (at -3.75 2.15 90) (size 0.3 1.2) (layers "B.Cu" "B.Paste" "B.Mask") (roundrect_rratio 0.25)
      (net 1 "GND") (pintype "passive"))
    (pad "19" smd roundrect locked (at -3.25 2.15 90) (size 0.3 1.2) (layers "B.Cu" "B.Paste" "B.Mask") (roundrect_rratio 0.25)
      (net 209 "/Camera interface/HPA09_N") (pintype "passive"))
    (pad "20" smd roundrect locked (at -2.75 2.15 90) (size 0.3 1.2) (layers "B.Cu" "B.Paste" "B.Mask") (roundrect_rratio 0.25)
      (net 208 "/Camera interface/HPA09_P") (pintype "passive"))
    (pad "21" smd roundrect locked (at -2.25 2.15 90) (size 0.3 1.2) (layers "B.Cu" "B.Paste" "B.Mask") (roundrect_rratio 0.25)
      (net 207 "/Camera interface/HPA08_N") (pintype "passive"))
    (pad "22" smd roundrect locked (at -1.75 2.15 90) (size 0.3 1.2) (layers "B.Cu" "B.Paste" "B.Mask") (roundrect_rratio 0.25)
      (net 206 "/Camera interface/HPA08_P") (pintype "passive"))
    (pad "23" smd roundrect locked (at -1.25 2.15 90) (size 0.3 1.2) (layers "B.Cu" "B.Paste" "B.Mask") (roundrect_rratio 0.25)
      (net 205 "/Camera interface/HPA07_N") (pintype "passive"))
    (pad "24" smd roundrect locked (at -0.75 2.15 90) (size 0.3 1.2) (layers "B.Cu" "B.Paste" "B.Mask") (roundrect_rratio 0.25)
      (net 204 "/Camera interface/HPA07_P") (pintype "passive"))
    (pad "25" smd roundrect locked (at -0.25 2.15 90) (size 0.3 1.2) (layers "B.Cu" "B.Paste" "B.Mask") (roundrect_rratio 0.25)
      (net 203 "/Camera interface/HPA06_N") (pintype "passive"))
    (pad "26" smd roundrect locked (at 0.248 2.15 90) (size 0.3 1.2) (layers "B.Cu" "B.Paste" "B.Mask") (roundrect_rratio 0.25)
      (net 202 "/Camera interface/HPA06_P") (pintype "passive"))
    (pad "27" smd roundrect locked (at 0.748 2.15 90) (size 0.3 1.2) (layers "B.Cu" "B.Paste" "B.Mask") (roundrect_rratio 0.25)
      (net 1 "GND") (pintype "passive"))
    (pad "28" smd roundrect locked (at 1.249 2.15 90) (size 0.3 1.2) (layers "B.Cu" "B.Paste" "B.Mask") (roundrect_rratio 0.25)
      (net 201 "/Camera interface/HPA05_CC_N") (pintype "passive"))
    (pad "29" smd roundrect locked (at 1.749 2.15 90) (size 0.3 1.2) (layers "B.Cu" "B.Paste" "B.Mask") (roundrect_rratio 0.25)
      (net 200 "/Camera interface/HPA05_CC_P") (pintype "passive"))
    (pad "30" smd roundrect locked (at 2.249 2.15 90) (size 0.3 1.2) (layers "B.Cu" "B.Paste" "B.Mask") (roundrect_rratio 0.25)
      (net 1 "GND") (pintype "passive"))
    (pad "31" smd roundrect locked (at 2.749 2.15 90) (size 0.3 1.2) (layers "B.Cu" "B.Paste" "B.Mask") (roundrect_rratio 0.25)
      (net 420 "unconnected-(J3-Pad31)") (pintype "passive+no_connect"))
    (pad "32" smd roundrect locked (at 3.249 2.15 90) (size 0.3 1.2) (layers "B.Cu" "B.Paste" "B.Mask") (roundrect_rratio 0.25)
      (net 199 "/Camera interface/CAM0_VSYNC") (pintype "passive"))
    (pad "33" smd roundrect locked (at 3.749 2.15 90) (size 0.3 1.2) (layers "B.Cu" "B.Paste" "B.Mask") (roundrect_rratio 0.25)
      (net 198 "/Camera interface/CAM0_RST") (pintype "passive"))
    (pad "34" smd roundrect locked (at 4.248 2.15 90) (size 0.3 1.2) (layers "B.Cu" "B.Paste" "B.Mask") (roundrect_rratio 0.25)
      (net 197 "/Camera interface/CAM1_VSYNC") (pintype "passive"))
    (pad "35" smd roundrect locked (at 4.748 2.15 90) (size 0.3 1.2) (layers "B.Cu" "B.Paste" "B.Mask") (roundrect_rratio 0.25)
      (net 421 "unconnected-(J3-Pad35)") (pintype "passive+no_connect"))
    (pad "36" smd roundrect locked (at 5.248 2.15 90) (size 0.3 1.2) (layers "B.Cu" "B.Paste" "B.Mask") (roundrect_rratio 0.25)
      (net 422 "unconnected-(J3-Pad36)") (pintype "passive+no_connect"))
    (pad "37" smd roundrect locked (at 5.749 2.15 90) (size 0.3 1.2) (layers "B.Cu" "B.Paste" "B.Mask") (roundrect_rratio 0.25)
      (net 423 "unconnected-(J3-Pad37)") (pintype "passive+no_connect"))
    (pad "38" smd roundrect locked (at 6.249 2.15 90) (size 0.3 1.2) (layers "B.Cu" "B.Paste" "B.Mask") (roundrect_rratio 0.25)
      (net 424 "unconnected-(J3-Pad38)") (pintype "passive+no_connect"))
    (pad "39" smd roundrect locked (at 6.749 2.15 90) (size 0.3 1.2) (layers "B.Cu" "B.Paste" "B.Mask") (roundrect_rratio 0.25)
      (net 196 "/Camera interface/CCI0_I2C_SDA_3V3") (pintype "passive"))
    (pad "40" smd roundrect locked (at 7.249 2.15 90) (size 0.3 1.2) (layers "B.Cu" "B.Paste" "B.Mask") (roundrect_rratio 0.25)
      (net 195 "/Camera interface/CCI0_I2C_SCL_3V3") (pintype "passive"))
    (pad "41" smd roundrect locked (at 7.749 2.15 90) (size 0.3 1.2) (layers "B.Cu" "B.Paste" "B.Mask") (roundrect_rratio 0.25)
      (net 194 "/Camera interface/CCI1_I2C_SDA_3V3") (pintype "passive"))
    (pad "42" smd roundrect locked (at 8.249 2.15 90) (size 0.3 1.2) (layers "B.Cu" "B.Paste" "B.Mask") (roundrect_rratio 0.25)
      (net 193 "/Camera interface/CCI1_I2C_SCL_3V3") (pintype "passive"))
    (pad "43" smd roundrect locked (at 8.749 2.15 90) (size 0.3 1.2) (layers "B.Cu" "B.Paste" "B.Mask") (roundrect_rratio 0.25)
      (net 425 "unconnected-(J3-Pad43)") (pintype "passive+no_connect"))
    (pad "44" smd roundrect locked (at 9.249 2.15 90) (size 0.3 1.2) (layers "B.Cu" "B.Paste" "B.Mask") (roundrect_rratio 0.25)
      (net 426 "unconnected-(J3-Pad44)") (pintype "passive+no_connect"))
    (pad "45" smd roundrect locked (at 9.749 2.15 90) (size 0.3 1.2) (layers "B.Cu" "B.Paste" "B.Mask") (roundrect_rratio 0.25)
      (net 427 "unconnected-(J3-Pad45)") (pintype "passive+no_connect"))
    (pad "46" smd roundrect locked (at 10.249 2.15 90) (size 0.3 1.2) (layers "B.Cu" "B.Paste" "B.Mask") (roundrect_rratio 0.25)
      (net 428 "unconnected-(J3-Pad46)") (pintype "passive+no_connect"))
    (pad "47" smd roundrect locked (at 10.749 2.15 90) (size 0.3 1.2) (layers "B.Cu" "B.Paste" "B.Mask") (roundrect_rratio 0.25)
      (net 20 "PL_3V3") (pintype "passive"))
    (pad "48" smd roundrect locked (at 11.249 2.15 90) (size 0.3 1.2) (layers "B.Cu" "B.Paste" "B.Mask") (roundrect_rratio 0.25)
      (net 20 "PL_3V3") (pintype "passive"))
    (pad "49" smd roundrect locked (at 11.749 2.15 90) (size 0.3 1.2) (layers "B.Cu" "B.Paste" "B.Mask") (roundrect_rratio 0.25)
      (net 8 "SOM_5V0") (pintype "passive"))
    (pad "50" smd roundrect locked (at 12.249 2.15 90) (size 0.3 1.2) (layers "B.Cu" "B.Paste" "B.Mask") (roundrect_rratio 0.25)
      (net 8 "SOM_5V0") (pintype "passive"))
    (pad "MP1" smd roundrect locked (at -14.201 4 90) (size 2.7 3) (layers "B.Cu" "B.Paste" "B.Mask") (roundrect_rratio 0.05)
      (net 1 "GND") (pinfunction "MP") (pintype "passive"))
    (pad "MP1" smd roundrect locked (at -14.198 0.3 90) (size 2.7 3) (layers "B.Cu" "B.Paste" "B.Mask") (roundrect_rratio 0.05)
      (net 1 "GND") (pinfunction "MP") (pintype "passive"))
    (pad "MP2" smd roundrect locked (at 14.198 0.3 90) (size 2.7 3) (layers "B.Cu" "B.Paste" "B.Mask") (roundrect_rratio 0.05)
      (net 1 "GND") (pinfunction "MP") (pintype "passive"))
    (pad "MP2" smd roundrect locked (at 14.198 4 90) (size 2.7 3) (layers "B.Cu" "B.Paste" "B.Mask") (roundrect_rratio 0.05)
      (net 1 "GND") (pinfunction "MP") (pintype "passive"))
  )
	(footprint "kria-k26-devboard-footprints:Spacer_Drill3mm_H1.5mm_9774015243R" (layer "B.Cu")
    (at 98.788558 122.024722 180)
    (property "Author" "Antmicro")
    (property "License" "Apache-2.0")
    (property "MPN" "9774015243R")
    (property "Manufacturer" "Würth Elektronik")
    (property "Sheetfile" "pcie-m2-key-e.kicad_sch")
    (property "Sheetname" "PCIE M2 key E ")
    (attr through_hole)
    (fp_text reference "SP5" (at -0.091442 -3.555278) (layer "B.SilkS")
        (effects (font (size 0.7 0.7) (thickness 0.15)) (justify left bottom mirror))
    )
    (fp_text value "Spacer_H1.5mm_9774015243R" (at -2.176 -4.25) (layer "B.Fab") hide
        (effects (font (size 0.7 0.7) (thickness 0.15)) (justify left bottom mirror))
    )
    (fp_text user "${REFERENCE}" (at -2.25 -5.5) (layer "B.Fab") hide
        (effects (font (size 0.7 0.7) (thickness 0.15)) (justify left bottom mirror))
    )
    (fp_text user "Author: Antmicro" (at -2.2 -6.75) (layer "B.Fab") hide
        (effects (font (size 0.7 0.7) (thickness 0.15)) (justify left bottom mirror))
    )
    (fp_text user "License: Apache-2.0" (at -2.2 -8) (layer "B.Fab") hide
        (effects (font (size 0.7 0.7) (thickness 0.15)) (justify left bottom mirror))
    )
    (pad "1" thru_hole circle (at 0 0 180) (size 5.3 5.3) (drill 3) (layers "B.Cu" "B.Mask")
      (net 1 "GND") (pintype "passive"))
  )
)
